(kicad_pcb
	(version 20260206)
	(generator "pcbnew")
	(generator_version "10.0")
	(general
		(thickness 1.6)
		(legacy_teardrops no)
	)
	(paper "A4")
	(title_block
		(title "Bryce Canyon_F.DPB_16315-1-OCP.brd")
		(comment 1 "Bryce Canyon / footprints 445-447 of 2223")
	)
	(layers
		(0 "F.Cu" signal "TOP")
		(4 "In1.Cu" signal "L2GND")
		(6 "In2.Cu" signal "L3")
		(8 "In3.Cu" signal "L4GND")
		(10 "In4.Cu" signal "L5")
		(12 "In5.Cu" signal "L6VCC")
		(14 "In6.Cu" signal "L7VCC")
		(16 "In7.Cu" signal "L8")
		(18 "In8.Cu" signal "L9GND")
		(20 "In9.Cu" signal "L10")
		(22 "In10.Cu" signal "L11GND")
		(2 "B.Cu" signal "BOTTOM")
		(9 "F.Adhes" user "F.Adhesive")
		(11 "B.Adhes" user "B.Adhesive")
		(13 "F.Paste" user "Package Geometry/Pastemask Top")
		(15 "B.Paste" user "Package Geometry/Pastemask Bottom")
		(5 "F.SilkS" user "Ref Des/Silkscreen Top")
		(7 "B.SilkS" user "Ref Des/Silkscreen Bottom")
		(1 "F.Mask" user "Board Geometry/Soldermask Top")
		(3 "B.Mask" user "Board Geometry/Soldermask Bottom")
		(17 "Dwgs.User" user "User.Drawings")
		(19 "Cmts.User" user "User.Comments")
		(21 "Eco1.User" user "User.Eco1")
		(23 "Eco2.User" user "User.Eco2")
		(25 "Edge.Cuts" user "Board Geometry/Outline")
		(27 "Margin" user)
		(31 "F.CrtYd" user "Package Geometry/Place Bound Top")
		(29 "B.CrtYd" user "Package Geometry/Place Bound Bottom")
		(35 "F.Fab" user "Ref Des/Assembly Top")
		(33 "B.Fab" user "Ref Des/Assembly Bottom")
	)
	(footprint ""
		(layer "F.Cu")
		(at 96.324928 -322.799964)
		(property "Reference" ""
			(at 0 0 0)
			(layer "F.SilkS")
			(hide yes)
			(effects
				(font
					(size 1.27 1.27)
				)
			)
		)
		(property "Value" "*"
			(at -8.398764 -8.057642 0)
			(unlocked yes)
			(layer "F.Fab")
			(hide yes)
			(effects
				(font
					(size 1.016 1.016)
					(thickness 0.1524)
				)
			)
		)
		(duplicate_pad_numbers_are_jumpers no)
		(fp_poly
			(pts
				(arc
					(start 7.3152 0)
					(mid 0 7.3152)
					(end -7.3152 0)
				)
				(arc
					(start -7.3152 -5.9944)
					(mid 0 -13.3096)
					(end 7.3152 -5.9944)
				)
			)
			(stroke
				(width 0)
				(type default)
			)
			(fill no)
			(layer "B.CrtYd")
		)
		(fp_poly
			(pts
				(arc
					(start 7.3152 0)
					(mid 0 7.3152)
					(end -7.3152 0)
				)
				(arc
					(start -7.3152 -5.9944)
					(mid 0 -13.3096)
					(end 7.3152 -5.9944)
				)
			)
			(stroke
				(width 0)
				(type default)
			)
			(fill no)
			(layer "F.CrtYd")
		)
		(fp_poly
			(pts
				(arc
					(start 7.3152 0)
					(mid 0 7.3152)
					(end -7.3152 0)
				)
				(arc
					(start -7.3152 -5.9944)
					(mid 0 -13.3096)
					(end 7.3152 -5.9944)
				)
			)
			(stroke
				(width 0)
				(type default)
			)
			(fill no)
			(layer "B.Fab")
		)
		(fp_poly
			(pts
				(arc
					(start 7.3152 0)
					(mid 0 7.3152)
					(end -7.3152 0)
				)
				(arc
					(start -7.3152 -5.9944)
					(mid 0 -13.3096)
					(end 7.3152 -5.9944)
				)
			)
			(stroke
				(width 0)
				(type default)
			)
			(fill no)
			(layer "F.Fab")
		)
		(pad "1" thru_hole oval
			(at 0 0)
			(size 14.0208 20.0152)
			(drill 0.0254
				(offset 0 -2.9972)
			)
			(layers "*.Cu" "*.Mask")
			(remove_unused_layers no)
			(net "Net_106")
			(clearance -1.002284)
			(thermal_gap 0.1524)
			(padstack
				(mode front_inner_back)
				(layer "Inner"
					(shape custom)
					(size 2.928012 2.928012)
					(options
						(anchor circle)
					)
					(primitives
						(gr_poly
							(pts
								(arc
									(start 4.571746 -2.084324)
									(mid 0.000333 7.430372)
									(end -4.571492 -2.084324)
								)
								(arc
									(start -4.571492 -2.084324)
									(mid -3.570296 -3.611977)
									(end -2.875026 -5.30098)
								)
								(arc
									(start -2.875026 -5.30098)
									(mid 0.000217 -7.43089)
									(end 2.87528 -5.30098)
								)
								(arc
									(start 2.87528 -5.30098)
									(mid 3.570511 -3.611956)
									(end 4.571746 -2.084324)
								)
							)
							(width 0)
							(fill yes)
						)
					)
					(clearance 0.1524)
				)
				(layer "B.Cu"
					(shape oval)
					(size 14.0208 20.0152)
					(offset 0 -2.9972)
					(clearance -1.002284)
				)
			)
		)
		(zone
			(layers "F.Cu" "B.Cu" "In1.Cu" "In2.Cu" "In3.Cu" "In4.Cu" "In5.Cu" "In6.Cu"
				"In7.Cu" "In8.Cu" "In9.Cu" "In10.Cu"
			)
			(hatch none 0.5)
			(connect_pads
				(clearance 0)
			)
			(min_thickness 0.25)
			(keepout
				(tracks not_allowed)
				(vias allowed)
				(pads allowed)
				(copperpour not_allowed)
				(footprints allowed)
			)
			(placement
				(enabled no)
				(sheetname "")
			)
			(fill
				(thermal_gap 0.5)
				(thermal_bridge_width 0.5)
				(island_removal_mode 0)
			)
			(polygon
				(pts
					(arc
						(start 89.314528 -328.794364)
						(mid 96.324928 -335.804764)
						(end 103.335328 -328.794364)
					)
					(arc
						(start 103.335328 -322.799964)
						(mid 96.324928 -315.789564)
						(end 89.314528 -322.799964)
					)
				)
			)
		)
	)
	(footprint ""
		(layer "F.Cu")
		(at 416.284664 -158.660592 -90)
		(property "Reference" "C312"
			(at 0 0 270)
			(layer "F.SilkS")
			(hide yes)
			(effects
				(font
					(size 1.27 1.27)
				)
			)
		)
		(property "Value" "SCD01U16V1KX-GP"
			(at -2.8321 -1.7399 270)
			(unlocked yes)
			(layer "F.Fab")
			(hide yes)
			(effects
				(font
					(size 1.016 1.016)
					(thickness 0.1524)
				)
			)
		)
		(property "Device Type" "C0201H13"
			(at -2.8321 -3.2639 270)
			(unlocked yes)
			(layer "F.Fab")
			(hide yes)
			(effects
				(font
					(size 1.016 1.016)
					(thickness 0.1524)
				)
			)
		)
		(duplicate_pad_numbers_are_jumpers no)
		(fp_rect
			(start -0.2794 0.6477)
			(end 0.2794 -0.6477)
			(stroke
				(width 0)
				(type default)
			)
			(fill no)
			(layer "F.CrtYd")
		)
		(fp_rect
			(start -0.2794 0.6477)
			(end 0.2794 -0.6477)
			(stroke
				(width 0)
				(type default)
			)
			(fill no)
			(layer "F.Fab")
		)
		(pad "1" smd custom
			(at 0 -0.2794 270)
			(size 0.0762 0.0762)
			(layers "F.Cu" "F.Mask" "F.Paste")
			(net "SAS_HDD_RX_P21")
			(options
				(clearance outline)
				(anchor circle)
			)
			(primitives
				(gr_poly
					(pts
						(arc
							(start 0.1524 -0.127)
							(mid 0.137521 -0.162921)
							(end 0.1016 -0.1778)
						)
						(arc
							(start -0.1016 -0.1778)
							(mid -0.137521 -0.162921)
							(end -0.1524 -0.127)
						)
						(arc
							(start -0.1524 0.127)
							(mid -0.137521 0.162921)
							(end -0.1016 0.1778)
						)
						(arc
							(start 0.1016 0.1778)
							(mid 0.137521 0.162921)
							(end 0.1524 0.127)
						)
					)
					(width 0)
					(fill yes)
				)
			)
		)
		(pad "2" smd custom
			(at 0 0.2794 270)
			(size 0.0762 0.0762)
			(layers "F.Cu" "F.Mask" "F.Paste")
			(net "PHY_SCC_A_TO_DRV_A_21_DP")
			(options
				(clearance outline)
				(anchor circle)
			)
			(primitives
				(gr_poly
					(pts
						(arc
							(start 0.1524 -0.127)
							(mid 0.137521 -0.162921)
							(end 0.1016 -0.1778)
						)
						(arc
							(start -0.1016 -0.1778)
							(mid -0.137521 -0.162921)
							(end -0.1524 -0.127)
						)
						(arc
							(start -0.1524 0.127)
							(mid -0.137521 0.162921)
							(end -0.1016 0.1778)
						)
						(arc
							(start 0.1016 0.1778)
							(mid 0.137521 0.162921)
							(end 0.1524 0.127)
						)
					)
					(width 0)
					(fill yes)
				)
			)
		)
	)
	(footprint ""
		(layer "F.Cu")
		(at 412.531052 -180.064918 -90)
		(property "Reference" "R617"
			(at 0 0 270)
			(layer "F.SilkS")
			(hide yes)
			(effects
				(font
					(size 1.27 1.27)
				)
			)
		)
		(property "Value" "220R3F-1-GP"
			(at -0.0254 -2.5146 270)
			(unlocked yes)
			(layer "F.Fab")
			(hide yes)
			(effects
				(font
					(size 1.016 1.016)
					(thickness 0.1524)
				)
			)
		)
		(property "Device Type" "R603H22"
			(at -0.0254 -4.0386 270)
			(unlocked yes)
			(layer "F.Fab")
			(hide yes)
			(effects
				(font
					(size 1.016 1.016)
					(thickness 0.1524)
				)
			)
		)
		(duplicate_pad_numbers_are_jumpers no)
		(fp_line
			(start -0.4826 0)
			(end -0.2032 0)
			(stroke
				(width 0.2032)
				(type default)
			)
			(layer "F.SilkS")
		)
		(fp_line
			(start 0.2032 0)
			(end 0.4826 0)
			(stroke
				(width 0.2032)
				(type default)
			)
			(layer "F.SilkS")
		)
		(fp_rect
			(start -0.5842 1.3335)
			(end 0.5842 -1.3335)
			(stroke
				(width 0)
				(type default)
			)
			(fill no)
			(layer "F.CrtYd")
		)
		(fp_rect
			(start -0.5842 1.3335)
			(end 0.5842 -1.3335)
			(stroke
				(width 0)
				(type default)
			)
			(fill no)
			(layer "F.Fab")
		)
		(pad "1" smd custom
			(at 0 -0.762 270)
			(size 0.2159 0.2159)
			(layers "F.Cu" "F.Mask" "F.Paste")
			(net "HDD_PRSNT_21")
			(options
				(clearance outline)
				(anchor circle)
			)
			(primitives
				(gr_poly
					(pts
						(arc
							(start -0.3302 -0.4318)
							(mid -0.402042 -0.402042)
							(end -0.4318 -0.3302)
						)
						(arc
							(start -0.4318 0.3302)
							(mid -0.402042 0.402042)
							(end -0.3302 0.4318)
						)
						(arc
							(start 0.3302 0.4318)
							(mid 0.402042 0.402042)
							(end 0.4318 0.3302)
						)
						(arc
							(start 0.4318 -0.3302)
							(mid 0.402042 -0.402042)
							(end 0.3302 -0.4318)
						)
					)
					(width 0)
					(fill yes)
				)
			)
		)
		(pad "2" smd custom
			(at 0 0.762 270)
			(size 0.2159 0.2159)
			(layers "F.Cu" "F.Mask" "F.Paste")
			(net "DRIVE_A_21_INS")
			(options
				(clearance outline)
				(anchor circle)
			)
			(primitives
				(gr_poly
					(pts
						(arc
							(start -0.3302 -0.4318)
							(mid -0.402042 -0.402042)
							(end -0.4318 -0.3302)
						)
						(arc
							(start -0.4318 0.3302)
							(mid -0.402042 0.402042)
							(end -0.3302 0.4318)
						)
						(arc
							(start 0.3302 0.4318)
							(mid 0.402042 0.402042)
							(end 0.4318 0.3302)
						)
						(arc
							(start 0.4318 -0.3302)
							(mid 0.402042 -0.402042)
							(end 0.3302 -0.4318)
						)
					)
					(width 0)
					(fill yes)
				)
			)
		)
	)
)
